# T6G (Grand Teton) — schematic netlist excerpt (pin names and nets, part order shuffled) for the footprints in the layout excerpt that follows; sources: Cadence DE-HDL packaged netlist, KiCad conversion of 04192023_DAF0TMB3IC0_F0TG_MB_C_brd_V02_OCP.brd

R4147  Q_RES  33.2 1% CHIP  pkg 0402LF  page 81 : A = PRSNT_CABLE_GPU_A2_ISO_R_N ; B = PRSNT_CABLE_GPU_A2_ISO_N
C2500  Q_CAP  22UF 4V 20% X6S  pkg C0402  page 74 : A = PVDD11_S3_P1 ; B = GND

(kicad_pcb
	(version 20260206)
	(generator "pcbnew")
	(generator_version "10.0")
	(general
		(thickness 1.6)
		(legacy_teardrops no)
	)
	(paper "A4")
	(title_block
		(title "04192023_DAF0TMB3IC0_F0TG_MB_C_brd_V02_OCP.brd")
		(comment 1 "Grand Teton / footprints 3310-3311 of 8354")
	)
	(layers
		(0 "F.Cu" signal "TOP")
		(4 "In1.Cu" signal "GND")
		(6 "In2.Cu" signal "IN1")
		(8 "In3.Cu" signal "GND1")
		(10 "In4.Cu" signal "IN2")
		(12 "In5.Cu" signal "GND2")
		(14 "In6.Cu" signal "IN3")
		(16 "In7.Cu" signal "GND3")
		(18 "In8.Cu" signal "VCC")
		(20 "In9.Cu" signal "VCC1")
		(22 "In10.Cu" signal "GND4")
		(24 "In11.Cu" signal "IN4")
		(26 "In12.Cu" signal "GND5")
		(28 "In13.Cu" signal "IN5")
		(30 "In14.Cu" signal "GND6")
		(32 "In15.Cu" signal "IN6")
		(34 "In16.Cu" signal "GND7")
		(2 "B.Cu" signal "BOTTOM")
		(9 "F.Adhes" user "F.Adhesive")
		(11 "B.Adhes" user "B.Adhesive")
		(13 "F.Paste" user "Package Geometry/Pastemask Top")
		(15 "B.Paste" user "Package Geometry/Pastemask Bottom")
		(5 "F.SilkS" user "Ref Des/Silkscreen Top")
		(7 "B.SilkS" user "Ref Des/Silkscreen Bottom")
		(1 "F.Mask" user "Board Geometry/Soldermask Top")
		(3 "B.Mask" user "Board Geometry/Soldermask Bottom")
		(17 "Dwgs.User" user "User.Drawings")
		(19 "Cmts.User" user "User.Comments")
		(21 "Eco1.User" user "User.Eco1")
		(23 "Eco2.User" user "User.Eco2")
		(25 "Edge.Cuts" user "Board Geometry/Outline")
		(27 "Margin" user)
		(31 "F.CrtYd" user "Package Geometry/Place Bound Top")
		(29 "B.CrtYd" user "Package Geometry/Place Bound Bottom")
		(35 "F.Fab" user "Ref Des/Assembly Top")
		(33 "B.Fab" user "Ref Des/Assembly Bottom")
	)
	(footprint ""
		(layer "F.Cu")
		(at 197.269608 -120.991376)
		(property "Reference" "R4147"
			(at 0 0 0)
			(layer "F.SilkS")
			(hide yes)
			(effects
				(font
					(size 1.27 1.27)
				)
			)
		)
		(property "Value" ""
			(at 0 0 0)
			(layer "F.Fab")
			(effects
				(font
					(size 1.27 1.27)
				)
			)
		)
		(duplicate_pad_numbers_are_jumpers no)
		(fp_line
			(start -0.7874 -0.4064)
			(end 0.7874 -0.4064)
			(stroke
				(width 0.1524)
				(type default)
			)
			(layer "F.SilkS")
		)
		(fp_line
			(start -0.7874 0.4064)
			(end -0.7874 -0.4064)
			(stroke
				(width 0.1524)
				(type default)
			)
			(layer "F.SilkS")
		)
		(fp_line
			(start 0.7874 -0.4064)
			(end 0.7874 0.4064)
			(stroke
				(width 0.1524)
				(type default)
			)
			(layer "F.SilkS")
		)
		(fp_line
			(start 0.7874 0.4064)
			(end -0.7874 0.4064)
			(stroke
				(width 0.1524)
				(type default)
			)
			(layer "F.SilkS")
		)
		(fp_line
			(start -0.67945 -0.305054)
			(end -0.12065 -0.305054)
			(stroke
				(width 0.1)
				(type default)
			)
			(layer "F.Fab")
		)
		(fp_line
			(start -0.67945 0.3048)
			(end -0.67945 -0.305054)
			(stroke
				(width 0.1)
				(type default)
			)
			(layer "F.Fab")
		)
		(fp_line
			(start -0.12065 -0.305054)
			(end -0.12065 -0.2794)
			(stroke
				(width 0.1)
				(type default)
			)
			(layer "F.Fab")
		)
		(fp_line
			(start -0.12065 -0.2794)
			(end 0.12065 -0.2794)
			(stroke
				(width 0.1)
				(type default)
			)
			(layer "F.Fab")
		)
		(fp_line
			(start -0.12065 0.2794)
			(end -0.12065 0.3048)
			(stroke
				(width 0.1)
				(type default)
			)
			(layer "F.Fab")
		)
		(fp_line
			(start -0.12065 0.3048)
			(end -0.67945 0.3048)
			(stroke
				(width 0.1)
				(type default)
			)
			(layer "F.Fab")
		)
		(fp_line
			(start 0.120396 0.2794)
			(end -0.12065 0.2794)
			(stroke
				(width 0.1)
				(type default)
			)
			(layer "F.Fab")
		)
		(fp_line
			(start 0.120396 0.3048)
			(end 0.120396 0.2794)
			(stroke
				(width 0.1)
				(type default)
			)
			(layer "F.Fab")
		)
		(fp_line
			(start 0.12065 -0.3048)
			(end 0.67945 -0.3048)
			(stroke
				(width 0.1)
				(type default)
			)
			(layer "F.Fab")
		)
		(fp_line
			(start 0.12065 -0.2794)
			(end 0.12065 -0.3048)
			(stroke
				(width 0.1)
				(type default)
			)
			(layer "F.Fab")
		)
		(fp_line
			(start 0.67945 -0.3048)
			(end 0.67945 0.3048)
			(stroke
				(width 0.1)
				(type default)
			)
			(layer "F.Fab")
		)
		(fp_line
			(start 0.67945 0.3048)
			(end 0.120396 0.3048)
			(stroke
				(width 0.1)
				(type default)
			)
			(layer "F.Fab")
		)
		(pad "1" smd circle
			(at -0.40005 0)
			(size 0 0)
			(layers "F.Cu" "F.Mask" "F.Paste")
			(net "PRSNT_CABLE_GPU_A2_ISO_R_N")
		)
		(pad "2" smd circle
			(at 0.40005 0)
			(size 0 0)
			(layers "F.Cu" "F.Mask" "F.Paste")
			(net "PRSNT_CABLE_GPU_A2_ISO_N")
		)
	)
	(footprint ""
		(layer "F.Cu")
		(at 108.627164 -261.748016 -90)
		(property "Reference" "C2500"
			(at 0 0 270)
			(layer "F.SilkS")
			(hide yes)
			(effects
				(font
					(size 1.27 1.27)
				)
			)
		)
		(property "Value" ""
			(at 0 0 270)
			(layer "F.Fab")
			(effects
				(font
					(size 1.27 1.27)
				)
			)
		)
		(duplicate_pad_numbers_are_jumpers no)
		(fp_line
			(start -0.7874 0.4064)
			(end -0.7874 -0.4064)
			(stroke
				(width 0.1524)
				(type default)
			)
			(layer "F.SilkS")
		)
		(fp_line
			(start 0.7874 0.4064)
			(end -0.7874 0.4064)
			(stroke
				(width 0.1524)
				(type default)
			)
			(layer "F.SilkS")
		)
		(fp_line
			(start -0.7874 -0.4064)
			(end 0.7874 -0.4064)
			(stroke
				(width 0.1524)
				(type default)
			)
			(layer "F.SilkS")
		)
		(fp_line
			(start 0.7874 -0.4064)
			(end 0.7874 0.4064)
			(stroke
				(width 0.1524)
				(type default)
			)
			(layer "F.SilkS")
		)
		(fp_line
			(start -0.67945 0.3048)
			(end -0.67945 -0.305054)
			(stroke
				(width 0.1)
				(type default)
			)
			(layer "F.Fab")
		)
		(fp_line
			(start -0.12065 0.3048)
			(end -0.67945 0.3048)
			(stroke
				(width 0.1)
				(type default)
			)
			(layer "F.Fab")
		)
		(fp_line
			(start 0.120396 0.3048)
			(end 0.120396 0.2794)
			(stroke
				(width 0.1)
				(type default)
			)
			(layer "F.Fab")
		)
		(fp_line
			(start 0.67945 0.3048)
			(end 0.120396 0.3048)
			(stroke
				(width 0.1)
				(type default)
			)
			(layer "F.Fab")
		)
		(fp_line
			(start -0.12065 0.2794)
			(end -0.12065 0.3048)
			(stroke
				(width 0.1)
				(type default)
			)
			(layer "F.Fab")
		)
		(fp_line
			(start 0.120396 0.2794)
			(end -0.12065 0.2794)
			(stroke
				(width 0.1)
				(type default)
			)
			(layer "F.Fab")
		)
		(fp_line
			(start -0.12065 -0.2794)
			(end 0.12065 -0.2794)
			(stroke
				(width 0.1)
				(type default)
			)
			(layer "F.Fab")
		)
		(fp_line
			(start 0.12065 -0.2794)
			(end 0.12065 -0.3048)
			(stroke
				(width 0.1)
				(type default)
			)
			(layer "F.Fab")
		)
		(fp_line
			(start 0.12065 -0.3048)
			(end 0.67945 -0.3048)
			(stroke
				(width 0.1)
				(type default)
			)
			(layer "F.Fab")
		)
		(fp_line
			(start 0.67945 -0.3048)
			(end 0.67945 0.3048)
			(stroke
				(width 0.1)
				(type default)
			)
			(layer "F.Fab")
		)
		(fp_line
			(start -0.67945 -0.305054)
			(end -0.12065 -0.305054)
			(stroke
				(width 0.1)
				(type default)
			)
			(layer "F.Fab")
		)
		(fp_line
			(start -0.12065 -0.305054)
			(end -0.12065 -0.2794)
			(stroke
				(width 0.1)
				(type default)
			)
			(layer "F.Fab")
		)
		(pad "1" smd circle
			(at -0.40005 0 270)
			(size 0 0)
			(layers "F.Cu" "F.Mask" "F.Paste")
			(net "PVDD11_S3_P1")
		)
		(pad "2" smd circle
			(at 0.40005 0 270)
			(size 0 0)
			(layers "F.Cu" "F.Mask" "F.Paste")
			(net "GND")
		)
	)
)
